# T6G (Grand Teton) — schematic netlist excerpt (pin names and nets, part order shuffled) for the footprints in the layout excerpt that follows; sources: Cadence DE-HDL packaged netlist, KiCad conversion of 04192023_DAF0TMB3IC0_F0TG_MB_C_brd_V02_OCP.brd

C785  Q_CAP  0.1UF 10V 10% X7S  pkg C0201  page 301 : A = P0V9_CPU0_RT_2D ; B = GND
C2207  Q_CAP  22UF 4V 20% X6S  pkg C0402  page 69 : A = PVDDCR_CPU1_P0 ; B = GND
C7020  Q_CAPP  470UF 2.5V 20% SPCAP  pkg SMLF  page 323 : A = P0V9_CPU1_RT0_2A ; B = GND

(kicad_pcb
	(version 20260206)
	(generator "pcbnew")
	(generator_version "10.0")
	(general
		(thickness 1.6)
		(legacy_teardrops no)
	)
	(paper "A4")
	(title_block
		(title "04192023_DAF0TMB3IC0_F0TG_MB_C_brd_V02_OCP.brd")
		(comment 1 "Grand Teton / footprints 7573-7575 of 8354")
	)
	(layers
		(0 "F.Cu" signal "TOP")
		(4 "In1.Cu" signal "GND")
		(6 "In2.Cu" signal "IN1")
		(8 "In3.Cu" signal "GND1")
		(10 "In4.Cu" signal "IN2")
		(12 "In5.Cu" signal "GND2")
		(14 "In6.Cu" signal "IN3")
		(16 "In7.Cu" signal "GND3")
		(18 "In8.Cu" signal "VCC")
		(20 "In9.Cu" signal "VCC1")
		(22 "In10.Cu" signal "GND4")
		(24 "In11.Cu" signal "IN4")
		(26 "In12.Cu" signal "GND5")
		(28 "In13.Cu" signal "IN5")
		(30 "In14.Cu" signal "GND6")
		(32 "In15.Cu" signal "IN6")
		(34 "In16.Cu" signal "GND7")
		(2 "B.Cu" signal "BOTTOM")
		(9 "F.Adhes" user "F.Adhesive")
		(11 "B.Adhes" user "B.Adhesive")
		(13 "F.Paste" user "Package Geometry/Pastemask Top")
		(15 "B.Paste" user "Package Geometry/Pastemask Bottom")
		(5 "F.SilkS" user "Ref Des/Silkscreen Top")
		(7 "B.SilkS" user "Ref Des/Silkscreen Bottom")
		(1 "F.Mask" user "Board Geometry/Soldermask Top")
		(3 "B.Mask" user "Board Geometry/Soldermask Bottom")
		(17 "Dwgs.User" user "User.Drawings")
		(19 "Cmts.User" user "User.Comments")
		(21 "Eco1.User" user "User.Eco1")
		(23 "Eco2.User" user "User.Eco2")
		(25 "Edge.Cuts" user "Board Geometry/Outline")
		(27 "Margin" user)
		(31 "F.CrtYd" user "Package Geometry/Place Bound Top")
		(29 "B.CrtYd" user "Package Geometry/Place Bound Bottom")
		(35 "F.Fab" user "Ref Des/Assembly Top")
		(33 "B.Fab" user "Ref Des/Assembly Bottom")
	)
	(footprint ""
		(layer "B.Cu")
		(at 61.967872 -381.11303)
		(property "Reference" "C7020"
			(at 2.02692 3.319272 0)
			(unlocked yes)
			(layer "B.SilkS")
			(effects
				(font
					(size 0.7874 0.5842)
					(thickness 0.1524)
				)
				(justify left mirror)
			)
		)
		(property "Value" ""
			(at 0 0 0)
			(layer "B.Fab")
			(effects
				(font
					(size 1.27 1.27)
				)
				(justify mirror)
			)
		)
		(duplicate_pad_numbers_are_jumpers no)
		(fp_line
			(start -4.53898 -2.15011)
			(end -4.53898 2.15011)
			(stroke
				(width 0.1524)
				(type default)
			)
			(layer "B.SilkS")
		)
		(fp_line
			(start -4.53898 2.15011)
			(end 4.53898 2.15011)
			(stroke
				(width 0.1524)
				(type default)
			)
			(layer "B.SilkS")
		)
		(fp_line
			(start 4.53898 -2.150618)
			(end 4.539742 2.152142)
			(stroke
				(width 0.1524)
				(type default)
			)
			(layer "B.SilkS")
		)
		(fp_line
			(start 4.53898 -2.15011)
			(end -4.53898 -2.15011)
			(stroke
				(width 0.1524)
				(type default)
			)
			(layer "B.SilkS")
		)
		(fp_line
			(start 4.53898 2.15011)
			(end 4.53898 -2.15011)
			(stroke
				(width 0.1524)
				(type default)
			)
			(layer "B.SilkS")
		)
		(fp_line
			(start 4.69138 -2.150618)
			(end 4.692396 2.161032)
			(stroke
				(width 0.1524)
				(type default)
			)
			(layer "B.SilkS")
		)
		(fp_line
			(start 4.83108 2.150364)
			(end 4.447794 2.149348)
			(stroke
				(width 0.1524)
				(type default)
			)
			(layer "B.SilkS")
		)
		(fp_line
			(start 4.84378 -2.150618)
			(end 4.53898 -2.150618)
			(stroke
				(width 0.1524)
				(type default)
			)
			(layer "B.SilkS")
		)
		(fp_line
			(start 4.84378 -2.150618)
			(end 4.842256 2.163064)
			(stroke
				(width 0.1524)
				(type default)
			)
			(layer "B.SilkS")
		)
		(fp_line
			(start -3.64998 -2.15011)
			(end -3.64998 2.15011)
			(stroke
				(width 0.1)
				(type default)
			)
			(layer "B.Fab")
		)
		(fp_line
			(start -3.64998 2.15011)
			(end 3.64998 2.15011)
			(stroke
				(width 0.1)
				(type default)
			)
			(layer "B.Fab")
		)
		(fp_line
			(start 3.64998 -2.15011)
			(end -3.64998 -2.15011)
			(stroke
				(width 0.1)
				(type default)
			)
			(layer "B.Fab")
		)
		(fp_line
			(start 3.64998 2.15011)
			(end 3.64998 -2.15011)
			(stroke
				(width 0.1)
				(type default)
			)
			(layer "B.Fab")
		)
		(fp_text user "-"
			(at -5.075174 2.326132 0)
			(unlocked yes)
			(layer "B.SilkS")
			(effects
				(font
					(size 1.905 1.4224)
					(thickness 0.1524)
				)
				(justify left mirror)
			)
		)
		(fp_text user "+"
			(at 4.302252 2.545842 0)
			(unlocked yes)
			(layer "B.SilkS")
			(effects
				(font
					(size 1.905 1.4224)
					(thickness 0.1524)
				)
				(justify left mirror)
			)
		)
		(fp_text user "-"
			(at -4.313174 -0.094488 0)
			(unlocked yes)
			(layer "B.Fab")
			(effects
				(font
					(size 1.905 1.4224)
					(thickness 0.1524)
				)
				(justify left mirror)
			)
		)
		(fp_text user "+"
			(at 6.214872 -0.337058 0)
			(unlocked yes)
			(layer "B.Fab")
			(effects
				(font
					(size 1.905 1.4224)
					(thickness 0.1524)
				)
				(justify left mirror)
			)
		)
		(pad "1" smd rect
			(at 3.199892 0 180)
			(size 2.413 2.8194)
			(layers "B.Cu" "B.Mask" "B.Paste")
			(net "P0V9_CPU1_RT0_2A")
		)
		(pad "2" smd rect
			(at -3.199892 0 180)
			(size 2.413 2.8194)
			(layers "B.Cu" "B.Mask" "B.Paste")
			(net "GND")
		)
	)
	(footprint ""
		(layer "B.Cu")
		(at 371.297454 -267.498576)
		(property "Reference" "C2207"
			(at 0 0 0)
			(layer "B.SilkS")
			(hide yes)
			(effects
				(font
					(size 1.27 1.27)
				)
				(justify mirror)
			)
		)
		(property "Value" ""
			(at 0 0 0)
			(layer "B.Fab")
			(effects
				(font
					(size 1.27 1.27)
				)
				(justify mirror)
			)
		)
		(duplicate_pad_numbers_are_jumpers no)
		(fp_line
			(start -0.7874 -0.4064)
			(end -0.7874 0.4064)
			(stroke
				(width 0.1524)
				(type default)
			)
			(layer "B.SilkS")
		)
		(fp_line
			(start -0.7874 0.4064)
			(end 0.7874 0.4064)
			(stroke
				(width 0.1524)
				(type default)
			)
			(layer "B.SilkS")
		)
		(fp_line
			(start 0.7874 -0.4064)
			(end -0.7874 -0.4064)
			(stroke
				(width 0.1524)
				(type default)
			)
			(layer "B.SilkS")
		)
		(fp_line
			(start 0.7874 0.4064)
			(end 0.7874 -0.4064)
			(stroke
				(width 0.1524)
				(type default)
			)
			(layer "B.SilkS")
		)
		(fp_line
			(start -0.67945 -0.3048)
			(end -0.67945 0.3048)
			(stroke
				(width 0.1)
				(type default)
			)
			(layer "B.Fab")
		)
		(fp_line
			(start -0.67945 0.3048)
			(end -0.120396 0.3048)
			(stroke
				(width 0.1)
				(type default)
			)
			(layer "B.Fab")
		)
		(fp_line
			(start -0.12065 -0.3048)
			(end -0.67945 -0.3048)
			(stroke
				(width 0.1)
				(type default)
			)
			(layer "B.Fab")
		)
		(fp_line
			(start -0.12065 -0.2794)
			(end -0.12065 -0.3048)
			(stroke
				(width 0.1)
				(type default)
			)
			(layer "B.Fab")
		)
		(fp_line
			(start -0.120396 0.2794)
			(end 0.12065 0.2794)
			(stroke
				(width 0.1)
				(type default)
			)
			(layer "B.Fab")
		)
		(fp_line
			(start -0.120396 0.3048)
			(end -0.120396 0.2794)
			(stroke
				(width 0.1)
				(type default)
			)
			(layer "B.Fab")
		)
		(fp_line
			(start 0.12065 -0.305054)
			(end 0.12065 -0.2794)
			(stroke
				(width 0.1)
				(type default)
			)
			(layer "B.Fab")
		)
		(fp_line
			(start 0.12065 -0.2794)
			(end -0.12065 -0.2794)
			(stroke
				(width 0.1)
				(type default)
			)
			(layer "B.Fab")
		)
		(fp_line
			(start 0.12065 0.2794)
			(end 0.12065 0.3048)
			(stroke
				(width 0.1)
				(type default)
			)
			(layer "B.Fab")
		)
		(fp_line
			(start 0.12065 0.3048)
			(end 0.67945 0.3048)
			(stroke
				(width 0.1)
				(type default)
			)
			(layer "B.Fab")
		)
		(fp_line
			(start 0.67945 -0.305054)
			(end 0.12065 -0.305054)
			(stroke
				(width 0.1)
				(type default)
			)
			(layer "B.Fab")
		)
		(fp_line
			(start 0.67945 0.3048)
			(end 0.67945 -0.305054)
			(stroke
				(width 0.1)
				(type default)
			)
			(layer "B.Fab")
		)
		(pad "1" smd circle
			(at 0.40005 0 180)
			(size 0 0)
			(layers "B.Cu" "B.Mask" "B.Paste")
			(net "PVDDCR_CPU1_P0")
		)
		(pad "2" smd circle
			(at -0.40005 0 180)
			(size 0 0)
			(layers "B.Cu" "B.Mask" "B.Paste")
			(net "GND")
		)
	)
	(footprint ""
		(layer "B.Cu")
		(at 415.146236 -396.393162 -90)
		(property "Reference" "C785"
			(at 0 0 90)
			(layer "B.SilkS")
			(hide yes)
			(effects
				(font
					(size 1.27 1.27)
				)
				(justify mirror)
			)
		)
		(property "Value" ""
			(at 0 0 90)
			(layer "B.Fab")
			(effects
				(font
					(size 1.27 1.27)
				)
				(justify mirror)
			)
		)
		(duplicate_pad_numbers_are_jumpers no)
		(fp_line
			(start -0.299974 0.150114)
			(end 0.299974 0.150114)
			(stroke
				(width 0.1)
				(type default)
			)
			(layer "B.Fab")
		)
		(fp_line
			(start 0.299974 0.150114)
			(end 0.299974 -0.150114)
			(stroke
				(width 0.1)
				(type default)
			)
			(layer "B.Fab")
		)
		(fp_line
			(start -0.299974 -0.150114)
			(end -0.299974 0.150114)
			(stroke
				(width 0.1)
				(type default)
			)
			(layer "B.Fab")
		)
		(fp_line
			(start 0.299974 -0.150114)
			(end -0.299974 -0.150114)
			(stroke
				(width 0.1)
				(type default)
			)
			(layer "B.Fab")
		)
		(pad "1" smd rect
			(at 0.2667 0 90)
			(size 0.3048 0.381)
			(layers "B.Cu" "B.Mask" "B.Paste")
			(net "P0V9_CPU0_RT_2D")
		)
		(pad "2" smd rect
			(at -0.2667 0 90)
			(size 0.3048 0.381)
			(layers "B.Cu" "B.Mask" "B.Paste")
			(net "GND")
		)
	)
)
